(kicad_pcb
	(version 20260206)
	(generator "pcbnew")
	(generator_version "10.0")
	(general
		(thickness 1.6)
		(legacy_teardrops no)
	)
	(paper "A4")
	(title_block
		(title "fcb — Lightning_FCB_BRD.brd")
		(comment 1 "Lightning (Wiwynn / Facebook NVMe JBOF) / footprints 25-31 of 495")
	)
	(layers
		(0 "F.Cu" signal "TOP")
		(4 "In1.Cu" signal "L2GND")
		(6 "In2.Cu" signal "L3VCC")
		(2 "B.Cu" signal "BOTTOM")
		(9 "F.Adhes" user "F.Adhesive")
		(11 "B.Adhes" user "B.Adhesive")
		(13 "F.Paste" user "Package Geometry/Pastemask Top")
		(15 "B.Paste" user "Package Geometry/Pastemask Bottom")
		(5 "F.SilkS" user "Ref Des/Silkscreen Top")
		(7 "B.SilkS" user "Ref Des/Silkscreen Bottom")
		(1 "F.Mask" user "Board Geometry/Soldermask Top")
		(3 "B.Mask" user "Board Geometry/Soldermask Bottom")
		(17 "Dwgs.User" user "User.Drawings")
		(19 "Cmts.User" user "User.Comments")
		(21 "Eco1.User" user "User.Eco1")
		(23 "Eco2.User" user "User.Eco2")
		(25 "Edge.Cuts" user "Board Geometry/Outline")
		(27 "Margin" user)
		(31 "F.CrtYd" user "Package Geometry/Place Bound Top")
		(29 "B.CrtYd" user "Package Geometry/Place Bound Bottom")
		(35 "F.Fab" user "Ref Des/Assembly Top")
		(33 "B.Fab" user "Ref Des/Assembly Bottom")
	)
	(footprint ""
		(layer "F.Cu")
		(at 32.399224 -173.65091 90)
		(property "Reference" "R17"
			(at 0 0 90)
			(layer "F.SilkS")
			(hide yes)
			(effects
				(font
					(size 1.27 1.27)
				)
			)
		)
		(property "Value" "100KR2F-L1-GP"
			(at 0.064008 -3.993896 90)
			(unlocked yes)
			(layer "F.Fab")
			(hide yes)
			(effects
				(font
					(size 1.016 1.016)
					(thickness 0.1524)
				)
			)
		)
		(property "Device Type" "R402H16"
			(at 0.064008 -5.517896 90)
			(unlocked yes)
			(layer "F.Fab")
			(hide yes)
			(effects
				(font
					(size 1.016 1.016)
					(thickness 0.1524)
				)
			)
		)
		(duplicate_pad_numbers_are_jumpers no)
		(fp_line
			(start 0.508 -0.9398)
			(end -0.508 -0.9398)
			(stroke
				(width 0.1524)
				(type default)
			)
			(layer "F.SilkS")
		)
		(fp_line
			(start -0.508 -0.9398)
			(end -0.508 0.9398)
			(stroke
				(width 0.1524)
				(type default)
			)
			(layer "F.SilkS")
		)
		(fp_rect
			(start -0.508 0.9398)
			(end 0.508 -0.9398)
			(stroke
				(width 0)
				(type default)
			)
			(fill no)
			(layer "F.CrtYd")
		)
		(fp_rect
			(start -0.508 0.9398)
			(end 0.508 -0.9398)
			(stroke
				(width 0)
				(type default)
			)
			(fill no)
			(layer "F.Fab")
		)
		(pad "1" smd custom
			(at 0 -0.4445 90)
			(size 0.1397 0.1397)
			(layers "F.Cu" "F.Mask" "F.Paste")
			(net "PWM_EXP_1A")
			(options
				(clearance outline)
				(anchor circle)
			)
			(primitives
				(gr_poly
					(pts
						(arc
							(start -0.1778 -0.2794)
							(mid -0.249642 -0.249642)
							(end -0.2794 -0.1778)
						)
						(arc
							(start -0.2794 0.1778)
							(mid -0.249642 0.249642)
							(end -0.1778 0.2794)
						)
						(arc
							(start 0.1778 0.2794)
							(mid 0.249642 0.249642)
							(end 0.2794 0.1778)
						)
						(arc
							(start 0.2794 -0.1778)
							(mid 0.249642 -0.249642)
							(end 0.1778 -0.2794)
						)
					)
					(width 0)
					(fill yes)
				)
			)
		)
		(pad "2" smd custom
			(at 0 0.4445 90)
			(size 0.1397 0.1397)
			(layers "F.Cu" "F.Mask" "F.Paste")
			(net "GND")
			(options
				(clearance outline)
				(anchor circle)
			)
			(primitives
				(gr_poly
					(pts
						(arc
							(start -0.1778 -0.2794)
							(mid -0.249642 -0.249642)
							(end -0.2794 -0.1778)
						)
						(arc
							(start -0.2794 0.1778)
							(mid -0.249642 0.249642)
							(end -0.1778 0.2794)
						)
						(arc
							(start 0.1778 0.2794)
							(mid 0.249642 0.249642)
							(end 0.2794 0.1778)
						)
						(arc
							(start 0.2794 -0.1778)
							(mid 0.249642 -0.249642)
							(end 0.1778 -0.2794)
						)
					)
					(width 0)
					(fill yes)
				)
			)
		)
	)
	(footprint ""
		(layer "F.Cu")
		(at 7.3406 -174.7774 180)
		(property "Reference" "C52"
			(at 0 0 180)
			(layer "F.SilkS")
			(hide yes)
			(effects
				(font
					(size 1.27 1.27)
				)
			)
		)
		(property "Value" "SCD1U50V3KX-GP"
			(at 0 -2.8194 180)
			(unlocked yes)
			(layer "F.Fab")
			(hide yes)
			(effects
				(font
					(size 1.016 1.016)
					(thickness 0.1524)
				)
			)
		)
		(property "Device Type" "C603H36"
			(at 0 -4.3434 180)
			(unlocked yes)
			(layer "F.Fab")
			(hide yes)
			(effects
				(font
					(size 1.016 1.016)
					(thickness 0.1524)
				)
			)
		)
		(duplicate_pad_numbers_are_jumpers no)
		(fp_line
			(start 0.508 0)
			(end -0.508 0)
			(stroke
				(width 0.2032)
				(type default)
			)
			(layer "F.SilkS")
		)
		(fp_rect
			(start -0.5842 1.3335)
			(end 0.5842 -1.3335)
			(stroke
				(width 0)
				(type default)
			)
			(fill no)
			(layer "F.CrtYd")
		)
		(fp_rect
			(start -0.5842 1.3335)
			(end 0.5842 -1.3335)
			(stroke
				(width 0)
				(type default)
			)
			(fill no)
			(layer "F.Fab")
		)
		(pad "1" smd custom
			(at 0 -0.762 180)
			(size 0.2159 0.2159)
			(layers "F.Cu" "F.Mask" "F.Paste")
			(net "P3V3")
			(options
				(clearance outline)
				(anchor circle)
			)
			(primitives
				(gr_poly
					(pts
						(arc
							(start -0.3302 -0.4318)
							(mid -0.402042 -0.402042)
							(end -0.4318 -0.3302)
						)
						(arc
							(start -0.4318 0.3302)
							(mid -0.402042 0.402042)
							(end -0.3302 0.4318)
						)
						(arc
							(start 0.3302 0.4318)
							(mid 0.402042 0.402042)
							(end 0.4318 0.3302)
						)
						(arc
							(start 0.4318 -0.3302)
							(mid 0.402042 -0.402042)
							(end 0.3302 -0.4318)
						)
					)
					(width 0)
					(fill yes)
				)
			)
		)
		(pad "2" smd custom
			(at 0 0.762 180)
			(size 0.2159 0.2159)
			(layers "F.Cu" "F.Mask" "F.Paste")
			(net "GND")
			(options
				(clearance outline)
				(anchor circle)
			)
			(primitives
				(gr_poly
					(pts
						(arc
							(start -0.3302 -0.4318)
							(mid -0.402042 -0.402042)
							(end -0.4318 -0.3302)
						)
						(arc
							(start -0.4318 0.3302)
							(mid -0.402042 0.402042)
							(end -0.3302 0.4318)
						)
						(arc
							(start 0.3302 0.4318)
							(mid 0.402042 0.402042)
							(end 0.4318 0.3302)
						)
						(arc
							(start 0.4318 -0.3302)
							(mid 0.402042 -0.402042)
							(end 0.3302 -0.4318)
						)
					)
					(width 0)
					(fill yes)
				)
			)
		)
	)
	(footprint ""
		(layer "F.Cu")
		(at 18.288 -271.7038 90)
		(property "Reference" "R179"
			(at 0 0 90)
			(layer "F.SilkS")
			(hide yes)
			(effects
				(font
					(size 1.27 1.27)
				)
			)
		)
		(property "Value" "0R1206-PAD-1-GP"
			(at 0 -5.0292 90)
			(unlocked yes)
			(layer "F.Fab")
			(hide yes)
			(effects
				(font
					(size 1.016 1.016)
					(thickness 0.1524)
				)
			)
		)
		(property "Device Type" "0R1206-PAD-1"
			(at 0 -6.5532 90)
			(unlocked yes)
			(layer "F.Fab")
			(hide yes)
			(effects
				(font
					(size 1.016 1.016)
					(thickness 0.1524)
				)
			)
		)
		(duplicate_pad_numbers_are_jumpers no)
		(fp_line
			(start 1.016 -2.2352)
			(end -1.016 -2.2352)
			(stroke
				(width 0.1524)
				(type default)
			)
			(layer "F.SilkS")
		)
		(fp_line
			(start -1.016 -2.2352)
			(end -1.016 2.2352)
			(stroke
				(width 0.1524)
				(type default)
			)
			(layer "F.SilkS")
		)
		(fp_line
			(start 1.016 2.2352)
			(end 1.016 -2.2352)
			(stroke
				(width 0.1524)
				(type default)
			)
			(layer "F.SilkS")
		)
		(fp_line
			(start -1.016 2.2352)
			(end 1.016 2.2352)
			(stroke
				(width 0.1524)
				(type default)
			)
			(layer "F.SilkS")
		)
		(fp_rect
			(start -1.0922 2.3114)
			(end 1.0922 -2.3114)
			(stroke
				(width 0)
				(type default)
			)
			(fill no)
			(layer "F.CrtYd")
		)
		(fp_poly
			(pts
				(xy -1.0922 -2.3114) (xy 1.0922 -2.3114) (xy 1.0922 2.3114) (xy -1.0922 2.3114)
			)
			(stroke
				(width 0)
				(type default)
			)
			(fill no)
			(layer "F.Fab")
		)
		(pad "1" smd rect
			(at 0 -1.397 90)
			(size 1.651 2.0574)
			(drill
				(offset 0 0.3937)
			)
			(layers "F.Cu" "F.Mask" "F.Paste")
			(net "P12V_FAN3")
		)
		(pad "2" smd rect
			(at 0 1.397 90)
			(size 1.651 2.0574)
			(drill
				(offset 0 -0.3937)
			)
			(layers "F.Cu" "F.Mask" "F.Paste")
			(net "P12V")
		)
	)
	(footprint ""
		(layer "F.Cu")
		(at 21.7678 -217.7288 90)
		(property "Reference" "R133"
			(at 0 0 90)
			(layer "F.SilkS")
			(hide yes)
			(effects
				(font
					(size 1.27 1.27)
				)
			)
		)
		(property "Value" "4K7R2F-GP"
			(at 0.064008 -3.993896 90)
			(unlocked yes)
			(layer "F.Fab")
			(hide yes)
			(effects
				(font
					(size 1.016 1.016)
					(thickness 0.1524)
				)
			)
		)
		(property "Device Type" "R402H16"
			(at 0.064008 -5.517896 90)
			(unlocked yes)
			(layer "F.Fab")
			(hide yes)
			(effects
				(font
					(size 1.016 1.016)
					(thickness 0.1524)
				)
			)
		)
		(duplicate_pad_numbers_are_jumpers no)
		(fp_line
			(start 0.508 -0.9398)
			(end -0.508 -0.9398)
			(stroke
				(width 0.1524)
				(type default)
			)
			(layer "F.SilkS")
		)
		(fp_line
			(start -0.508 -0.9398)
			(end -0.508 0.9398)
			(stroke
				(width 0.1524)
				(type default)
			)
			(layer "F.SilkS")
		)
		(fp_rect
			(start -0.508 0.9398)
			(end 0.508 -0.9398)
			(stroke
				(width 0)
				(type default)
			)
			(fill no)
			(layer "F.CrtYd")
		)
		(fp_rect
			(start -0.508 0.9398)
			(end 0.508 -0.9398)
			(stroke
				(width 0)
				(type default)
			)
			(fill no)
			(layer "F.Fab")
		)
		(pad "1" smd custom
			(at 0 -0.4445 90)
			(size 0.1397 0.1397)
			(layers "F.Cu" "F.Mask" "F.Paste")
			(net "P3V3")
			(options
				(clearance outline)
				(anchor circle)
			)
			(primitives
				(gr_poly
					(pts
						(arc
							(start -0.1778 -0.2794)
							(mid -0.249642 -0.249642)
							(end -0.2794 -0.1778)
						)
						(arc
							(start -0.2794 0.1778)
							(mid -0.249642 0.249642)
							(end -0.1778 0.2794)
						)
						(arc
							(start 0.1778 0.2794)
							(mid 0.249642 0.249642)
							(end 0.2794 0.1778)
						)
						(arc
							(start 0.2794 -0.1778)
							(mid 0.249642 -0.249642)
							(end 0.1778 -0.2794)
						)
					)
					(width 0)
					(fill yes)
				)
			)
		)
		(pad "2" smd custom
			(at 0 0.4445 90)
			(size 0.1397 0.1397)
			(layers "F.Cu" "F.Mask" "F.Paste")
			(net "PWM_OUT_FAN3")
			(options
				(clearance outline)
				(anchor circle)
			)
			(primitives
				(gr_poly
					(pts
						(arc
							(start -0.1778 -0.2794)
							(mid -0.249642 -0.249642)
							(end -0.2794 -0.1778)
						)
						(arc
							(start -0.2794 0.1778)
							(mid -0.249642 0.249642)
							(end -0.1778 0.2794)
						)
						(arc
							(start 0.1778 0.2794)
							(mid 0.249642 0.249642)
							(end 0.2794 0.1778)
						)
						(arc
							(start 0.2794 -0.1778)
							(mid 0.249642 -0.249642)
							(end 0.1778 -0.2794)
						)
					)
					(width 0)
					(fill yes)
				)
			)
		)
	)
	(footprint ""
		(layer "F.Cu")
		(at 24.70531 -151.325834)
		(property "Reference" "R10"
			(at 0 0 0)
			(layer "F.SilkS")
			(hide yes)
			(effects
				(font
					(size 1.27 1.27)
				)
			)
		)
		(property "Value" "1MR2J-1-GP"
			(at 0.064008 -3.993896 0)
			(unlocked yes)
			(layer "F.Fab")
			(hide yes)
			(effects
				(font
					(size 1.016 1.016)
					(thickness 0.1524)
				)
			)
		)
		(property "Device Type" "R402H16"
			(at 0.064008 -5.517896 0)
			(unlocked yes)
			(layer "F.Fab")
			(hide yes)
			(effects
				(font
					(size 1.016 1.016)
					(thickness 0.1524)
				)
			)
		)
		(duplicate_pad_numbers_are_jumpers no)
		(fp_line
			(start -0.508 -0.9398)
			(end -0.508 0.9398)
			(stroke
				(width 0.1524)
				(type default)
			)
			(layer "F.SilkS")
		)
		(fp_line
			(start 0.508 -0.9398)
			(end -0.508 -0.9398)
			(stroke
				(width 0.1524)
				(type default)
			)
			(layer "F.SilkS")
		)
		(fp_rect
			(start -0.508 0.9398)
			(end 0.508 -0.9398)
			(stroke
				(width 0)
				(type default)
			)
			(fill no)
			(layer "F.CrtYd")
		)
		(fp_rect
			(start -0.508 0.9398)
			(end 0.508 -0.9398)
			(stroke
				(width 0)
				(type default)
			)
			(fill no)
			(layer "F.Fab")
		)
		(pad "1" smd custom
			(at 0 -0.4445)
			(size 0.1397 0.1397)
			(layers "F.Cu" "F.Mask" "F.Paste")
			(net "NCT7904_CASEOPEN")
			(options
				(clearance outline)
				(anchor circle)
			)
			(primitives
				(gr_poly
					(pts
						(arc
							(start -0.1778 -0.2794)
							(mid -0.249642 -0.249642)
							(end -0.2794 -0.1778)
						)
						(arc
							(start -0.2794 0.1778)
							(mid -0.249642 0.249642)
							(end -0.1778 0.2794)
						)
						(arc
							(start 0.1778 0.2794)
							(mid 0.249642 0.249642)
							(end 0.2794 0.1778)
						)
						(arc
							(start 0.2794 -0.1778)
							(mid 0.249642 -0.249642)
							(end 0.1778 -0.2794)
						)
					)
					(width 0)
					(fill yes)
				)
			)
		)
		(pad "2" smd custom
			(at 0 0.4445)
			(size 0.1397 0.1397)
			(layers "F.Cu" "F.Mask" "F.Paste")
			(net "NCT7904_3VSB")
			(options
				(clearance outline)
				(anchor circle)
			)
			(primitives
				(gr_poly
					(pts
						(arc
							(start -0.1778 -0.2794)
							(mid -0.249642 -0.249642)
							(end -0.2794 -0.1778)
						)
						(arc
							(start -0.2794 0.1778)
							(mid -0.249642 0.249642)
							(end -0.1778 0.2794)
						)
						(arc
							(start 0.1778 0.2794)
							(mid 0.249642 0.249642)
							(end 0.2794 0.1778)
						)
						(arc
							(start 0.2794 -0.1778)
							(mid 0.249642 -0.249642)
							(end 0.1778 -0.2794)
						)
					)
					(width 0)
					(fill yes)
				)
			)
		)
	)
	(footprint ""
		(layer "F.Cu")
		(at 19.3294 -277.0124 -90)
		(property "Reference" "TC16"
			(at 0 0 270)
			(layer "F.SilkS")
			(hide yes)
			(effects
				(font
					(size 1.27 1.27)
				)
			)
		)
		(property "Value" "ST15U25VDM-1-GP"
			(at 0 -9.6012 270)
			(unlocked yes)
			(layer "F.Fab")
			(hide yes)
			(effects
				(font
					(size 1.016 1.016)
					(thickness 0.1524)
				)
			)
		)
		(property "Device Type" "CT7343H79"
			(at 0 -11.1252 270)
			(unlocked yes)
			(layer "F.Fab")
			(hide yes)
			(effects
				(font
					(size 1.016 1.016)
					(thickness 0.1524)
				)
			)
		)
		(duplicate_pad_numbers_are_jumpers no)
		(fp_line
			(start -2.286 4.8768)
			(end -2.286 2.032)
			(stroke
				(width 0.1524)
				(type default)
			)
			(layer "F.SilkS")
		)
		(fp_line
			(start 2.286 4.8768)
			(end -2.286 4.8768)
			(stroke
				(width 0.1524)
				(type default)
			)
			(layer "F.SilkS")
		)
		(fp_line
			(start 2.286 2.032)
			(end 2.286 4.8768)
			(stroke
				(width 0.1524)
				(type default)
			)
			(layer "F.SilkS")
		)
		(fp_line
			(start 2.286 -2.032)
			(end 2.286 -4.8768)
			(stroke
				(width 0.1524)
				(type default)
			)
			(layer "F.SilkS")
		)
		(fp_line
			(start 2.1082 -4.699)
			(end -2.1082 -4.699)
			(stroke
				(width 0.508)
				(type default)
			)
			(layer "F.SilkS")
		)
		(fp_line
			(start -2.286 -4.8768)
			(end -2.286 -2.032)
			(stroke
				(width 0.1524)
				(type default)
			)
			(layer "F.SilkS")
		)
		(fp_line
			(start 2.286 -4.8768)
			(end -2.286 -4.8768)
			(stroke
				(width 0.1524)
				(type default)
			)
			(layer "F.SilkS")
		)
		(fp_rect
			(start -2.1463 3.6449)
			(end 2.1463 -3.6449)
			(stroke
				(width 0)
				(type default)
			)
			(fill no)
			(layer "F.CrtYd")
		)
		(fp_poly
			(pts
				(xy -2.54 4.953) (xy -2.54 4.2926) (xy -3.81 4.2926) (xy -3.81 -4.2926) (xy -2.54 -4.2926) (xy -2.54 -4.953)
				(xy 2.54 -4.953) (xy 2.54 -4.2926) (xy 3.81 -4.2926) (xy 3.81 -1.6256) (xy 2.1463 -1.6256) (xy 2.1463 -3.6449)
				(xy -2.1463 -3.6449) (xy -2.1463 3.6449) (xy 2.1463 3.6449) (xy 2.1463 -1.6129) (xy 3.81 -1.6129)
				(xy 3.81 4.2926) (xy 2.54 4.2926) (xy 2.54 4.953)
			)
			(stroke
				(width 0)
				(type default)
			)
			(fill no)
			(layer "F.CrtYd")
		)
		(fp_rect
			(start -2.54 4.953)
			(end 2.54 -4.953)
			(stroke
				(width 0)
				(type default)
			)
			(fill no)
			(layer "F.Fab")
		)
		(fp_rect
			(start -3.81 4.2926)
			(end -2.54 -4.2926)
			(stroke
				(width 0)
				(type default)
			)
			(fill no)
			(layer "F.Fab")
		)
		(fp_rect
			(start 2.54 4.2926)
			(end 3.81 -4.2926)
			(stroke
				(width 0)
				(type default)
			)
			(fill no)
			(layer "F.Fab")
		)
		(pad "1" smd rect
			(at 0 -3.1496 270)
			(size 2.413 2.286)
			(layers "F.Cu" "F.Mask" "F.Paste")
			(net "P12V")
		)
		(pad "2" smd rect
			(at 0 3.1496 270)
			(size 2.413 2.286)
			(layers "F.Cu" "F.Mask" "F.Paste")
			(net "GND")
		)
		(zone
			(layer "F.Cu")
			(hatch none 0.5)
			(connect_pads
				(clearance 0)
			)
			(min_thickness 0.25)
			(keepout
				(tracks allowed)
				(vias not_allowed)
				(pads allowed)
				(copperpour not_allowed)
				(footprints allowed)
			)
			(placement
				(enabled no)
				(sheetname "")
			)
			(fill
				(thermal_gap 0.5)
				(thermal_bridge_width 0.5)
				(island_removal_mode 0)
			)
			(polygon
				(pts
					(xy 14.732 -278.5237) (xy 14.732 -275.5011) (xy 17.6276 -275.5011) (xy 17.9578 -275.5011) (xy 17.9578 -278.5237)
					(xy 17.6276 -278.5237)
				)
			)
		)
		(zone
			(layer "F.Cu")
			(hatch none 0.5)
			(connect_pads
				(clearance 0)
			)
			(min_thickness 0.25)
			(keepout
				(tracks allowed)
				(vias not_allowed)
				(pads allowed)
				(copperpour not_allowed)
				(footprints allowed)
			)
			(placement
				(enabled no)
				(sheetname "")
			)
			(fill
				(thermal_gap 0.5)
				(thermal_bridge_width 0.5)
				(island_removal_mode 0)
			)
			(polygon
				(pts
					(xy 21.0185 -275.5011) (xy 23.9268 -275.5011) (xy 23.9268 -278.5237) (xy 21.0312 -278.5237) (xy 20.701 -278.5237)
					(xy 20.701 -275.5011)
				)
			)
		)
	)
	(footprint ""
		(layer "F.Cu")
		(at 45.83811 -160.825434)
		(property "Reference" "C6"
			(at 0 0 0)
			(layer "F.SilkS")
			(hide yes)
			(effects
				(font
					(size 1.27 1.27)
				)
			)
		)
		(property "Value" "SC4D7U6D3V2MX-GP-U"
			(at -1.524 -1.905 0)
			(unlocked yes)
			(layer "F.Fab")
			(hide yes)
			(effects
				(font
					(size 1.016 1.016)
					(thickness 0.1524)
				)
			)
		)
		(property "Device Type" "C402-TO0D2H26"
			(at -1.524 -3.429 0)
			(unlocked yes)
			(layer "F.Fab")
			(hide yes)
			(effects
				(font
					(size 1.016 1.016)
					(thickness 0.1524)
				)
			)
		)
		(duplicate_pad_numbers_are_jumpers no)
		(fp_rect
			(start -0.4826 0.889)
			(end 0.4826 -0.889)
			(stroke
				(width 0)
				(type default)
			)
			(fill no)
			(layer "F.CrtYd")
		)
		(fp_rect
			(start -0.4826 0.889)
			(end 0.4826 -0.889)
			(stroke
				(width 0)
				(type default)
			)
			(fill no)
			(layer "F.Fab")
		)
		(pad "1" smd custom
			(at 0 -0.4572)
			(size 0.1524 0.1524)
			(layers "F.Cu" "F.Mask" "F.Paste")
			(net "P3V3")
			(options
				(clearance outline)
				(anchor circle)
			)
			(primitives
				(gr_poly
					(pts
						(arc
							(start -0.254 0.3048)
							(mid -0.325842 0.275042)
							(end -0.3556 0.2032)
						)
						(arc
							(start -0.3556 -0.2032)
							(mid -0.325842 -0.275042)
							(end -0.254 -0.3048)
						)
						(arc
							(start 0.254 -0.3048)
							(mid 0.325842 -0.275042)
							(end 0.3556 -0.2032)
						)
						(arc
							(start 0.3556 0.2032)
							(mid 0.325842 0.275042)
							(end 0.254 0.3048)
						)
					)
					(width 0)
					(fill yes)
				)
			)
		)
		(pad "2" smd custom
			(at 0 0.4572)
			(size 0.1524 0.1524)
			(layers "F.Cu" "F.Mask" "F.Paste")
			(net "GND")
			(options
				(clearance outline)
				(anchor circle)
			)
			(primitives
				(gr_poly
					(pts
						(arc
							(start -0.254 0.3048)
							(mid -0.325842 0.275042)
							(end -0.3556 0.2032)
						)
						(arc
							(start -0.3556 -0.2032)
							(mid -0.325842 -0.275042)
							(end -0.254 -0.3048)
						)
						(arc
							(start 0.254 -0.3048)
							(mid 0.325842 -0.275042)
							(end 0.3556 -0.2032)
						)
						(arc
							(start 0.3556 0.2032)
							(mid 0.325842 0.275042)
							(end 0.254 0.3048)
						)
					)
					(width 0)
					(fill yes)
				)
			)
		)
	)
)
